FILE_TYPE = MACRO_DRAWING;
SET COLOR_WIRE YELLOW;
SET COLOR_PROP ORANGE;
SET COLOR_DOT WHITE;
SET COLOR_ARC YELLOW;
SET COLOR_BODY GREEN;
SET COLOR_NOTE PURPLE;
SET PROP_DISPLAY VALUE;
SET PAGE_NUMBER P212;
FORCEADD QUANTA_TITLE_BLOCK_C..1
(0 0);
FORCEPROP 1 LAST CUSTOM_TXT_CDS <NAME_2>
J 0
(-3175 50);
FORCEPROP 1 LAST CUSTOM_TXT_CDS <NAME_1>
J 0
(-3175 175);
FORCEPROP 1 LAST CUSTOM_TXT_CDS <Q_NUMBER>
J 0
(-1403 103);
DISPLAY 1.212766 (-1403 103);
FORCEPROP 1 LAST CUSTOM_TXT_CDS <Q_PROJ>
J 0
(-2382 102);
DISPLAY 1.212766 (-2382 102);
FORCEPROP 1 LAST CUSTOM_TXT_CDS <Q_REV>
J 0
(-184 103);
DISPLAY 1.212766 (-184 103);
FORCEPROP 1 LAST CUSTOM_TXT_CDS <CON_LAST_MODIFIED>
J 0
(-1885 15);
DISPLAY 0.978723 (-1885 15);
FORCEPROP 1 LAST CUSTOM_TXT_CDS <CON_PAGE_NUM> OF <CON_TOTAL_PAGES>
J 0
(-446 18);
DISPLAY 0.978723 (-446 18);
FORCEPROP 1 LAST Q_DEPT BU9
J 1
(-3763 49);
DISPLAY 1.957447 (-3763 49);
PAINT GREEN (-3763 49);
FORCEPROP 1 LAST Q_TITLE HOLE
J 0
(-9366 26);
DISPLAY 2.446809 (-9366 26);
PAINT GREEN (-9366 26);
FORCEPROP 1 LAST COMMENT_BODY TRUE
J 0
(12 -13);
DISPLAY 0.978723 (12 -13);
PAINT GREEN (12 -13);
DISPLAY INVISIBLE (12 -13);
FORCEPROP 2 LAST CDS_LIB pure_quanta
J 0
(0 0);
DISPLAY INVISIBLE (0 0);
FORCEPROP 1 LAST CDS_LMAN_SYM_OUTLINE -9475,6775,100,-125
J 0
(0 0);
DISPLAY 0.468085 (0 0);
PAINT GREEN (0 0);
DISPLAY INVISIBLE (0 0);
FORCEPROP 2 LAST PAGE_BORDER TRUE
J 0
(-7890 5250);
DISPLAY 0.638298 (-7890 5250);
PAINT PINK (-7890 5250);
DISPLAY INVISIBLE (-7890 5250);
FORCEPROP 2 LAST CDS_XR_PAGE_TITLE CR-213 : @T6G_MB_LIB.T6G(SCH_1):PAGE213
J 0
(-7890 5250);
DISPLAY 0.638298 (-7890 5250);
PAINT PINK (-7890 5250);
DISPLAY INVISIBLE (-7890 5250);
FORCEPROP 2 LAST CUSTOM_TXT_CDS <XR_PAGE_TITLE>
J 0
(-7890 5250);
DISPLAY 0.638298 (-7890 5250);
PAINT PINK (-7890 5250);
DISPLAY INVISIBLE (-7890 5250);
FORCEPROP 0 LAST CDS_CON_LAST_MODIFIED Wed Mar 09 21:48:45 2022
J 0
(-1885 15);
DISPLAY INVISIBLE (-1885 15);
QUIT
